(kicad_pcb
	(version 20260206)
	(generator "pcbnew")
	(generator_version "10.0")
	(general
		(thickness 1.6)
		(legacy_teardrops no)
	)
	(paper "A4")
	(title_block
		(title "01162023_DA0F0TEBIF0_F0T_Expander_BD_F_brd_V02_OCP.brd")
		(comment 1 "Grand Teton / footprints 4420-4425 of 9728")
	)
	(layers
		(0 "F.Cu" signal "TOP")
		(4 "In1.Cu" signal "GND")
		(6 "In2.Cu" signal "VCC")
		(8 "In3.Cu" signal "VCC1")
		(10 "In4.Cu" signal "GND1")
		(12 "In5.Cu" signal "IN1")
		(14 "In6.Cu" signal "GND2")
		(16 "In7.Cu" signal "IN2")
		(18 "In8.Cu" signal "GND3")
		(20 "In9.Cu" signal "IN3")
		(22 "In10.Cu" signal "GND4")
		(24 "In11.Cu" signal "IN4")
		(26 "In12.Cu" signal "GND5")
		(28 "In13.Cu" signal "IN5")
		(30 "In14.Cu" signal "GND6")
		(32 "In15.Cu" signal "IN6")
		(34 "In16.Cu" signal "GND7")
		(2 "B.Cu" signal "BOTTOM")
		(9 "F.Adhes" user "F.Adhesive")
		(11 "B.Adhes" user "B.Adhesive")
		(13 "F.Paste" user "Package Geometry/Pastemask Top")
		(15 "B.Paste" user "Package Geometry/Pastemask Bottom")
		(5 "F.SilkS" user "Ref Des/Silkscreen Top")
		(7 "B.SilkS" user "Ref Des/Silkscreen Bottom")
		(1 "F.Mask" user "Board Geometry/Soldermask Top")
		(3 "B.Mask" user "Board Geometry/Soldermask Bottom")
		(17 "Dwgs.User" user "User.Drawings")
		(19 "Cmts.User" user "User.Comments")
		(21 "Eco1.User" user "User.Eco1")
		(23 "Eco2.User" user "User.Eco2")
		(25 "Edge.Cuts" user "Board Geometry/Outline")
		(27 "Margin" user)
		(31 "F.CrtYd" user "Package Geometry/Place Bound Top")
		(29 "B.CrtYd" user "Package Geometry/Place Bound Bottom")
		(35 "F.Fab" user "Ref Des/Assembly Top")
		(33 "B.Fab" user "Ref Des/Assembly Bottom")
	)
	(footprint ""
		(layer "F.Cu")
		(at 230.848408 -311.533032 90)
		(property "Reference" "R843"
			(at 0 0 90)
			(layer "F.SilkS")
			(hide yes)
			(effects
				(font
					(size 1.27 1.27)
				)
			)
		)
		(property "Value" ""
			(at 0 0 90)
			(layer "F.Fab")
			(effects
				(font
					(size 1.27 1.27)
				)
			)
		)
		(duplicate_pad_numbers_are_jumpers no)
		(fp_line
			(start 0.7874 -0.4064)
			(end 0.7874 0.4064)
			(stroke
				(width 0.1524)
				(type default)
			)
			(layer "F.SilkS")
		)
		(fp_line
			(start -0.7874 -0.4064)
			(end 0.7874 -0.4064)
			(stroke
				(width 0.1524)
				(type default)
			)
			(layer "F.SilkS")
		)
		(fp_line
			(start 0.7874 0.4064)
			(end -0.7874 0.4064)
			(stroke
				(width 0.1524)
				(type default)
			)
			(layer "F.SilkS")
		)
		(fp_line
			(start -0.7874 0.4064)
			(end -0.7874 -0.4064)
			(stroke
				(width 0.1524)
				(type default)
			)
			(layer "F.SilkS")
		)
		(fp_line
			(start -0.12065 -0.305054)
			(end -0.12065 -0.2794)
			(stroke
				(width 0.1)
				(type default)
			)
			(layer "F.Fab")
		)
		(fp_line
			(start -0.67945 -0.305054)
			(end -0.12065 -0.305054)
			(stroke
				(width 0.1)
				(type default)
			)
			(layer "F.Fab")
		)
		(fp_line
			(start 0.67945 -0.3048)
			(end 0.67945 0.3048)
			(stroke
				(width 0.1)
				(type default)
			)
			(layer "F.Fab")
		)
		(fp_line
			(start 0.12065 -0.3048)
			(end 0.67945 -0.3048)
			(stroke
				(width 0.1)
				(type default)
			)
			(layer "F.Fab")
		)
		(fp_line
			(start 0.12065 -0.2794)
			(end 0.12065 -0.3048)
			(stroke
				(width 0.1)
				(type default)
			)
			(layer "F.Fab")
		)
		(fp_line
			(start -0.12065 -0.2794)
			(end 0.12065 -0.2794)
			(stroke
				(width 0.1)
				(type default)
			)
			(layer "F.Fab")
		)
		(fp_line
			(start 0.120396 0.2794)
			(end -0.12065 0.2794)
			(stroke
				(width 0.1)
				(type default)
			)
			(layer "F.Fab")
		)
		(fp_line
			(start -0.12065 0.2794)
			(end -0.12065 0.3048)
			(stroke
				(width 0.1)
				(type default)
			)
			(layer "F.Fab")
		)
		(fp_line
			(start 0.67945 0.3048)
			(end 0.120396 0.3048)
			(stroke
				(width 0.1)
				(type default)
			)
			(layer "F.Fab")
		)
		(fp_line
			(start 0.120396 0.3048)
			(end 0.120396 0.2794)
			(stroke
				(width 0.1)
				(type default)
			)
			(layer "F.Fab")
		)
		(fp_line
			(start -0.12065 0.3048)
			(end -0.67945 0.3048)
			(stroke
				(width 0.1)
				(type default)
			)
			(layer "F.Fab")
		)
		(fp_line
			(start -0.67945 0.3048)
			(end -0.67945 -0.305054)
			(stroke
				(width 0.1)
				(type default)
			)
			(layer "F.Fab")
		)
		(pad "1" smd circle
			(at -0.40005 0 90)
			(size 0 0)
			(layers "F.Cu" "F.Mask" "F.Paste")
			(net "P1V25_PEX1_VCC")
		)
		(pad "2" smd circle
			(at 0.40005 0 90)
			(size 0 0)
			(layers "F.Cu" "F.Mask" "F.Paste")
			(net "PWRGD_P1V25_PEX1")
		)
	)
	(footprint ""
		(layer "F.Cu")
		(at 372.9228 -238.643922)
		(property "Reference" "R6408"
			(at 0 0 0)
			(layer "F.SilkS")
			(hide yes)
			(effects
				(font
					(size 1.27 1.27)
				)
			)
		)
		(property "Value" ""
			(at 0 0 0)
			(layer "F.Fab")
			(effects
				(font
					(size 1.27 1.27)
				)
			)
		)
		(duplicate_pad_numbers_are_jumpers no)
		(fp_line
			(start -0.7874 -0.4064)
			(end 0.7874 -0.4064)
			(stroke
				(width 0.1524)
				(type default)
			)
			(layer "F.SilkS")
		)
		(fp_line
			(start -0.7874 0.4064)
			(end -0.7874 -0.4064)
			(stroke
				(width 0.1524)
				(type default)
			)
			(layer "F.SilkS")
		)
		(fp_line
			(start 0.7874 -0.4064)
			(end 0.7874 0.4064)
			(stroke
				(width 0.1524)
				(type default)
			)
			(layer "F.SilkS")
		)
		(fp_line
			(start 0.7874 0.4064)
			(end -0.7874 0.4064)
			(stroke
				(width 0.1524)
				(type default)
			)
			(layer "F.SilkS")
		)
		(fp_line
			(start -0.67945 -0.305054)
			(end -0.12065 -0.305054)
			(stroke
				(width 0.1)
				(type default)
			)
			(layer "F.Fab")
		)
		(fp_line
			(start -0.67945 0.3048)
			(end -0.67945 -0.305054)
			(stroke
				(width 0.1)
				(type default)
			)
			(layer "F.Fab")
		)
		(fp_line
			(start -0.12065 -0.305054)
			(end -0.12065 -0.2794)
			(stroke
				(width 0.1)
				(type default)
			)
			(layer "F.Fab")
		)
		(fp_line
			(start -0.12065 -0.2794)
			(end 0.12065 -0.2794)
			(stroke
				(width 0.1)
				(type default)
			)
			(layer "F.Fab")
		)
		(fp_line
			(start -0.12065 0.2794)
			(end -0.12065 0.3048)
			(stroke
				(width 0.1)
				(type default)
			)
			(layer "F.Fab")
		)
		(fp_line
			(start -0.12065 0.3048)
			(end -0.67945 0.3048)
			(stroke
				(width 0.1)
				(type default)
			)
			(layer "F.Fab")
		)
		(fp_line
			(start 0.120396 0.2794)
			(end -0.12065 0.2794)
			(stroke
				(width 0.1)
				(type default)
			)
			(layer "F.Fab")
		)
		(fp_line
			(start 0.120396 0.3048)
			(end 0.120396 0.2794)
			(stroke
				(width 0.1)
				(type default)
			)
			(layer "F.Fab")
		)
		(fp_line
			(start 0.12065 -0.3048)
			(end 0.67945 -0.3048)
			(stroke
				(width 0.1)
				(type default)
			)
			(layer "F.Fab")
		)
		(fp_line
			(start 0.12065 -0.2794)
			(end 0.12065 -0.3048)
			(stroke
				(width 0.1)
				(type default)
			)
			(layer "F.Fab")
		)
		(fp_line
			(start 0.67945 -0.3048)
			(end 0.67945 0.3048)
			(stroke
				(width 0.1)
				(type default)
			)
			(layer "F.Fab")
		)
		(fp_line
			(start 0.67945 0.3048)
			(end 0.120396 0.3048)
			(stroke
				(width 0.1)
				(type default)
			)
			(layer "F.Fab")
		)
		(pad "1" smd circle
			(at -0.40005 0)
			(size 0 0)
			(layers "F.Cu" "F.Mask" "F.Paste")
			(net "PWRGD_P3V3_AUX_R2")
		)
		(pad "2" smd circle
			(at 0.40005 0)
			(size 0 0)
			(layers "F.Cu" "F.Mask" "F.Paste")
			(net "PWRGD_P3V3_AUX_R")
		)
	)
	(footprint ""
		(layer "F.Cu")
		(at 115.847114 -253.178564 180)
		(property "Reference" "PC46"
			(at 0 0 180)
			(layer "F.SilkS")
			(hide yes)
			(effects
				(font
					(size 1.27 1.27)
				)
			)
		)
		(property "Value" ""
			(at 0 0 180)
			(layer "F.Fab")
			(effects
				(font
					(size 1.27 1.27)
				)
			)
		)
		(duplicate_pad_numbers_are_jumpers no)
		(fp_line
			(start 1.524 0.762)
			(end -1.524 0.762)
			(stroke
				(width 0.1524)
				(type default)
			)
			(layer "F.SilkS")
		)
		(fp_line
			(start 1.524 -0.762)
			(end 1.524 0.762)
			(stroke
				(width 0.1524)
				(type default)
			)
			(layer "F.SilkS")
		)
		(fp_line
			(start -1.524 0.762)
			(end -1.524 -0.762)
			(stroke
				(width 0.1524)
				(type default)
			)
			(layer "F.SilkS")
		)
		(fp_line
			(start -1.524 -0.762)
			(end 1.524 -0.762)
			(stroke
				(width 0.1524)
				(type default)
			)
			(layer "F.SilkS")
		)
		(fp_line
			(start 1.1049 0.724916)
			(end 1.1049 -0.724916)
			(stroke
				(width 0.1)
				(type default)
			)
			(layer "F.Fab")
		)
		(fp_line
			(start 1.1049 -0.724916)
			(end -1.1049 -0.724916)
			(stroke
				(width 0.1)
				(type default)
			)
			(layer "F.Fab")
		)
		(fp_line
			(start -1.1049 0.724916)
			(end 1.1049 0.724916)
			(stroke
				(width 0.1)
				(type default)
			)
			(layer "F.Fab")
		)
		(fp_line
			(start -1.1049 -0.724916)
			(end -1.1049 0.724916)
			(stroke
				(width 0.1)
				(type default)
			)
			(layer "F.Fab")
		)
		(pad "1" smd rect
			(at -0.889 0)
			(size 1.016 1.27)
			(layers "F.Cu" "F.Mask" "F.Paste")
			(net "P0V8_PEX0_VREF")
		)
		(pad "2" smd rect
			(at 0.889 0)
			(size 1.016 1.27)
			(layers "F.Cu" "F.Mask" "F.Paste")
			(net "GND")
		)
	)
	(footprint ""
		(layer "F.Cu")
		(at 87.982298 -306.06492 90)
		(property "Reference" "R3893"
			(at 0 0 90)
			(layer "F.SilkS")
			(hide yes)
			(effects
				(font
					(size 1.27 1.27)
				)
			)
		)
		(property "Value" ""
			(at 0 0 90)
			(layer "F.Fab")
			(effects
				(font
					(size 1.27 1.27)
				)
			)
		)
		(duplicate_pad_numbers_are_jumpers no)
		(fp_line
			(start 0.7874 -0.4064)
			(end 0.7874 0.4064)
			(stroke
				(width 0.1524)
				(type default)
			)
			(layer "F.SilkS")
		)
		(fp_line
			(start -0.7874 -0.4064)
			(end 0.7874 -0.4064)
			(stroke
				(width 0.1524)
				(type default)
			)
			(layer "F.SilkS")
		)
		(fp_line
			(start 0.7874 0.4064)
			(end -0.7874 0.4064)
			(stroke
				(width 0.1524)
				(type default)
			)
			(layer "F.SilkS")
		)
		(fp_line
			(start -0.7874 0.4064)
			(end -0.7874 -0.4064)
			(stroke
				(width 0.1524)
				(type default)
			)
			(layer "F.SilkS")
		)
		(fp_line
			(start -0.12065 -0.305054)
			(end -0.12065 -0.2794)
			(stroke
				(width 0.1)
				(type default)
			)
			(layer "F.Fab")
		)
		(fp_line
			(start -0.67945 -0.305054)
			(end -0.12065 -0.305054)
			(stroke
				(width 0.1)
				(type default)
			)
			(layer "F.Fab")
		)
		(fp_line
			(start 0.67945 -0.3048)
			(end 0.67945 0.3048)
			(stroke
				(width 0.1)
				(type default)
			)
			(layer "F.Fab")
		)
		(fp_line
			(start 0.12065 -0.3048)
			(end 0.67945 -0.3048)
			(stroke
				(width 0.1)
				(type default)
			)
			(layer "F.Fab")
		)
		(fp_line
			(start 0.12065 -0.2794)
			(end 0.12065 -0.3048)
			(stroke
				(width 0.1)
				(type default)
			)
			(layer "F.Fab")
		)
		(fp_line
			(start -0.12065 -0.2794)
			(end 0.12065 -0.2794)
			(stroke
				(width 0.1)
				(type default)
			)
			(layer "F.Fab")
		)
		(fp_line
			(start 0.120396 0.2794)
			(end -0.12065 0.2794)
			(stroke
				(width 0.1)
				(type default)
			)
			(layer "F.Fab")
		)
		(fp_line
			(start -0.12065 0.2794)
			(end -0.12065 0.3048)
			(stroke
				(width 0.1)
				(type default)
			)
			(layer "F.Fab")
		)
		(fp_line
			(start 0.67945 0.3048)
			(end 0.120396 0.3048)
			(stroke
				(width 0.1)
				(type default)
			)
			(layer "F.Fab")
		)
		(fp_line
			(start 0.120396 0.3048)
			(end 0.120396 0.2794)
			(stroke
				(width 0.1)
				(type default)
			)
			(layer "F.Fab")
		)
		(fp_line
			(start -0.12065 0.3048)
			(end -0.67945 0.3048)
			(stroke
				(width 0.1)
				(type default)
			)
			(layer "F.Fab")
		)
		(fp_line
			(start -0.67945 0.3048)
			(end -0.67945 -0.305054)
			(stroke
				(width 0.1)
				(type default)
			)
			(layer "F.Fab")
		)
		(pad "1" smd circle
			(at -0.40005 0 90)
			(size 0 0)
			(layers "F.Cu" "F.Mask" "F.Paste")
			(net "SMB_PEX0_SLAVE_SDA")
		)
		(pad "2" smd circle
			(at 0.40005 0 90)
			(size 0 0)
			(layers "F.Cu" "F.Mask" "F.Paste")
			(net "SMB_PEX0_R_SDA")
		)
	)
	(footprint ""
		(layer "F.Cu")
		(at 211.722716 -22.867366 90)
		(property "Reference" "C3924"
			(at 0 0 90)
			(layer "F.SilkS")
			(hide yes)
			(effects
				(font
					(size 1.27 1.27)
				)
			)
		)
		(property "Value" ""
			(at 0 0 90)
			(layer "F.Fab")
			(effects
				(font
					(size 1.27 1.27)
				)
			)
		)
		(duplicate_pad_numbers_are_jumpers no)
		(fp_line
			(start 0.7874 -0.4064)
			(end 0.7874 0.4064)
			(stroke
				(width 0.1524)
				(type default)
			)
			(layer "F.SilkS")
		)
		(fp_line
			(start -0.7874 -0.4064)
			(end 0.7874 -0.4064)
			(stroke
				(width 0.1524)
				(type default)
			)
			(layer "F.SilkS")
		)
		(fp_line
			(start 0.7874 0.4064)
			(end -0.7874 0.4064)
			(stroke
				(width 0.1524)
				(type default)
			)
			(layer "F.SilkS")
		)
		(fp_line
			(start -0.7874 0.4064)
			(end -0.7874 -0.4064)
			(stroke
				(width 0.1524)
				(type default)
			)
			(layer "F.SilkS")
		)
		(fp_line
			(start -0.12065 -0.305054)
			(end -0.12065 -0.2794)
			(stroke
				(width 0.1)
				(type default)
			)
			(layer "F.Fab")
		)
		(fp_line
			(start -0.67945 -0.305054)
			(end -0.12065 -0.305054)
			(stroke
				(width 0.1)
				(type default)
			)
			(layer "F.Fab")
		)
		(fp_line
			(start 0.67945 -0.3048)
			(end 0.67945 0.3048)
			(stroke
				(width 0.1)
				(type default)
			)
			(layer "F.Fab")
		)
		(fp_line
			(start 0.12065 -0.3048)
			(end 0.67945 -0.3048)
			(stroke
				(width 0.1)
				(type default)
			)
			(layer "F.Fab")
		)
		(fp_line
			(start 0.12065 -0.2794)
			(end 0.12065 -0.3048)
			(stroke
				(width 0.1)
				(type default)
			)
			(layer "F.Fab")
		)
		(fp_line
			(start -0.12065 -0.2794)
			(end 0.12065 -0.2794)
			(stroke
				(width 0.1)
				(type default)
			)
			(layer "F.Fab")
		)
		(fp_line
			(start 0.120396 0.2794)
			(end -0.12065 0.2794)
			(stroke
				(width 0.1)
				(type default)
			)
			(layer "F.Fab")
		)
		(fp_line
			(start -0.12065 0.2794)
			(end -0.12065 0.3048)
			(stroke
				(width 0.1)
				(type default)
			)
			(layer "F.Fab")
		)
		(fp_line
			(start 0.67945 0.3048)
			(end 0.120396 0.3048)
			(stroke
				(width 0.1)
				(type default)
			)
			(layer "F.Fab")
		)
		(fp_line
			(start 0.120396 0.3048)
			(end 0.120396 0.2794)
			(stroke
				(width 0.1)
				(type default)
			)
			(layer "F.Fab")
		)
		(fp_line
			(start -0.12065 0.3048)
			(end -0.67945 0.3048)
			(stroke
				(width 0.1)
				(type default)
			)
			(layer "F.Fab")
		)
		(fp_line
			(start -0.67945 0.3048)
			(end -0.67945 -0.305054)
			(stroke
				(width 0.1)
				(type default)
			)
			(layer "F.Fab")
		)
		(pad "1" smd circle
			(at -0.40005 0 90)
			(size 0 0)
			(layers "F.Cu" "F.Mask" "F.Paste")
			(net "P12V_SSD7")
		)
		(pad "2" smd circle
			(at 0.40005 0 90)
			(size 0 0)
			(layers "F.Cu" "F.Mask" "F.Paste")
			(net "GND")
		)
	)
	(footprint ""
		(layer "F.Cu")
		(at 317.090806 -55.663846 90)
		(property "Reference" "PU69"
			(at -1.304036 2.718562 90)
			(unlocked yes)
			(layer "F.SilkS")
			(effects
				(font
					(size 0.7874 0.5842)
					(thickness 0.1524)
				)
				(justify left)
			)
		)
		(property "Value" ""
			(at 0 0 90)
			(layer "F.Fab")
			(effects
				(font
					(size 1.27 1.27)
				)
			)
		)
		(duplicate_pad_numbers_are_jumpers no)
		(fp_line
			(start 1.943608 -1.549908)
			(end 1.943608 1.549908)
			(stroke
				(width 0.1524)
				(type default)
			)
			(layer "F.SilkS")
		)
		(fp_line
			(start -1.943608 -1.549908)
			(end 1.943608 -1.549908)
			(stroke
				(width 0.1524)
				(type default)
			)
			(layer "F.SilkS")
		)
		(fp_line
			(start 1.943608 1.549908)
			(end -1.943608 1.549908)
			(stroke
				(width 0.1524)
				(type default)
			)
			(layer "F.SilkS")
		)
		(fp_line
			(start -1.943608 1.549908)
			(end -1.943608 -1.549908)
			(stroke
				(width 0.1524)
				(type default)
			)
			(layer "F.SilkS")
		)
		(fp_poly
			(pts
				(xy -2.019808 -1.549908) (xy -1.257808 -1.549908) (xy -1.257808 -1.880108) (xy -2.019808 -1.880108)
			)
			(stroke
				(width 0)
				(type default)
			)
			(fill yes)
			(layer "F.SilkS")
		)
		(fp_line
			(start 1.549908 -1.549908)
			(end 1.549908 1.549908)
			(stroke
				(width 0.1)
				(type default)
			)
			(layer "F.Fab")
		)
		(fp_line
			(start -1.549908 -1.549908)
			(end 1.549908 -1.549908)
			(stroke
				(width 0.1)
				(type default)
			)
			(layer "F.Fab")
		)
		(fp_line
			(start 1.549908 1.549908)
			(end -1.549908 1.549908)
			(stroke
				(width 0.1)
				(type default)
			)
			(layer "F.Fab")
		)
		(fp_line
			(start -1.549908 1.549908)
			(end -1.549908 -1.549908)
			(stroke
				(width 0.1)
				(type default)
			)
			(layer "F.Fab")
		)
		(fp_poly
			(pts
				(xy -2.019808 -1.549908) (xy -1.257808 -1.549908) (xy -1.257808 -1.880108) (xy -2.019808 -1.880108)
			)
			(stroke
				(width 0)
				(type default)
			)
			(fill yes)
			(layer "F.Fab")
		)
		(pad "1" smd rect
			(at -1.500124 -1.249934)
			(size 0.2794 0.6096)
			(layers "F.Cu" "F.Mask" "F.Paste")
			(net "P3V3_SSD11")
		)
		(pad "2" smd rect
			(at -1.500124 -0.750062)
			(size 0.2794 0.6096)
			(layers "F.Cu" "F.Mask" "F.Paste")
			(net "P3V3_SSD11")
		)
		(pad "3" smd rect
			(at -1.500124 -0.249936)
			(size 0.2794 0.6096)
			(layers "F.Cu" "F.Mask" "F.Paste")
			(net "P3V3_SSD11")
		)
		(pad "4" smd rect
			(at -1.500124 0.249936)
			(size 0.2794 0.6096)
			(layers "F.Cu" "F.Mask" "F.Paste")
			(net "P3V3_SSD11")
		)
		(pad "5" smd rect
			(at -1.500124 0.750062)
			(size 0.2794 0.6096)
			(layers "F.Cu" "F.Mask" "F.Paste")
			(net "P3V3_SSD11")
		)
		(pad "6" smd rect
			(at -1.500124 1.249934)
			(size 0.2794 0.6096)
			(layers "F.Cu" "F.Mask" "F.Paste")
			(net "GND")
		)
		(pad "7" smd rect
			(at 1.500124 1.249934)
			(size 0.2794 0.6096)
			(layers "F.Cu" "F.Mask" "F.Paste")
			(net "P3V3_SSD11_SS")
		)
		(pad "8" smd rect
			(at 1.500124 0.750062)
			(size 0.2794 0.6096)
			(layers "F.Cu" "F.Mask" "F.Paste")
			(net "PWRGD_P3V3_SSD11")
		)
		(pad "9" smd rect
			(at 1.500124 0.249936)
			(size 0.2794 0.6096)
			(layers "F.Cu" "F.Mask" "F.Paste")
			(net "P3V3_SSD11_OCP")
		)
		(pad "10" smd rect
			(at 1.500124 -0.249936)
			(size 0.2794 0.6096)
			(layers "F.Cu" "F.Mask" "F.Paste")
			(net "P5V_AUX")
		)
		(pad "11" smd rect
			(at 1.500124 -0.750062)
			(size 0.2794 0.6096)
			(layers "F.Cu" "F.Mask" "F.Paste")
			(net "SSD11_AUX_P3V3_EN_R")
		)
		(pad "12" smd rect
			(at 1.500124 -1.249934)
			(size 0.2794 0.6096)
			(layers "F.Cu" "F.Mask" "F.Paste")
			(net "P3V3_AUX")
		)
		(pad "13" smd rect
			(at 0 0 90)
			(size 1.9812 2.7178)
			(layers "F.Cu" "F.Mask" "F.Paste")
			(net "P3V3_AUX")
		)
		(zone
			(layer "F.Cu")
			(hatch none 0.5)
			(connect_pads
				(clearance 0)
			)
			(min_thickness 0.25)
			(keepout
				(tracks not_allowed)
				(vias allowed)
				(pads allowed)
				(copperpour not_allowed)
				(footprints allowed)
			)
			(placement
				(enabled no)
				(sheetname "")
			)
			(fill
				(thermal_gap 0.5)
				(thermal_bridge_width 0.5)
				(island_removal_mode 0)
			)
			(polygon
				(pts
					(xy 315.541406 -56.806846) (xy 315.668406 -56.806846) (xy 318.640206 -56.806846) (xy 318.640714 -56.806846)
					(xy 318.640714 -54.520846) (xy 318.640206 -54.520846) (xy 318.513206 -54.520846) (xy 317.090806 -54.520846)
					(xy 317.090806 -54.622446) (xy 318.513206 -54.622446) (xy 318.513206 -56.705246) (xy 315.668406 -56.705246)
					(xy 315.668406 -54.622446) (xy 317.065406 -54.622446) (xy 317.065406 -54.520846) (xy 315.668406 -54.520846)
					(xy 315.541406 -54.520846) (xy 315.540898 -54.520846) (xy 315.540898 -56.806846)
				)
			)
		)
	)
)
